(kicad_pcb
	(version 20260206)
	(generator "pcbnew")
	(generator_version "10.0")
	(general
		(thickness 1.6)
		(legacy_teardrops no)
	)
	(paper "A4")
	(title_block
		(title "9052_F0T_PDB_Converter_Brick_F_V03_1208_1600_OCP.brd")
		(comment 1 "Grand Teton / footprints 510-515 of 578")
	)
	(layers
		(0 "F.Cu" signal "TOP")
		(4 "In1.Cu" signal "GND")
		(6 "In2.Cu" signal "IN1")
		(8 "In3.Cu" signal "GND1")
		(10 "In4.Cu" signal "VCC")
		(12 "In5.Cu" signal "VCC1")
		(14 "In6.Cu" signal "GND2")
		(16 "In7.Cu" signal "IN2")
		(18 "In8.Cu" signal "GND3")
		(2 "B.Cu" signal "BOTTOM")
		(9 "F.Adhes" user "F.Adhesive")
		(11 "B.Adhes" user "B.Adhesive")
		(13 "F.Paste" user "Package Geometry/Pastemask Top")
		(15 "B.Paste" user "Package Geometry/Pastemask Bottom")
		(5 "F.SilkS" user "Ref Des/Silkscreen Top")
		(7 "B.SilkS" user "Ref Des/Silkscreen Bottom")
		(1 "F.Mask" user "Board Geometry/Soldermask Top")
		(3 "B.Mask" user "Board Geometry/Soldermask Bottom")
		(17 "Dwgs.User" user "User.Drawings")
		(19 "Cmts.User" user "User.Comments")
		(21 "Eco1.User" user "User.Eco1")
		(23 "Eco2.User" user "User.Eco2")
		(25 "Edge.Cuts" user "Board Geometry/Outline")
		(27 "Margin" user)
		(31 "F.CrtYd" user "Package Geometry/Place Bound Top")
		(29 "B.CrtYd" user "Package Geometry/Place Bound Bottom")
		(35 "F.Fab" user "Ref Des/Assembly Top")
		(33 "B.Fab" user "Ref Des/Assembly Bottom")
	)
	(footprint ""
		(layer "B.Cu")
		(at 212.344 -67.183 90)
		(property "Reference" "R94"
			(at 0 0 90)
			(layer "B.SilkS")
			(hide yes)
			(effects
				(font
					(size 1.27 1.27)
				)
				(justify mirror)
			)
		)
		(property "Value" ""
			(at 0 0 90)
			(layer "B.Fab")
			(effects
				(font
					(size 1.27 1.27)
				)
				(justify mirror)
			)
		)
		(duplicate_pad_numbers_are_jumpers no)
		(fp_line
			(start 0.7874 -0.4064)
			(end -0.7874 -0.4064)
			(stroke
				(width 0.1524)
				(type default)
			)
			(layer "B.SilkS")
		)
		(fp_line
			(start -0.7874 -0.4064)
			(end -0.7874 0.4064)
			(stroke
				(width 0.1524)
				(type default)
			)
			(layer "B.SilkS")
		)
		(fp_line
			(start 0.7874 0.4064)
			(end 0.7874 -0.4064)
			(stroke
				(width 0.1524)
				(type default)
			)
			(layer "B.SilkS")
		)
		(fp_line
			(start -0.7874 0.4064)
			(end 0.7874 0.4064)
			(stroke
				(width 0.1524)
				(type default)
			)
			(layer "B.SilkS")
		)
		(fp_line
			(start 0.67945 -0.305054)
			(end 0.12065 -0.305054)
			(stroke
				(width 0.1)
				(type default)
			)
			(layer "B.Fab")
		)
		(fp_line
			(start 0.12065 -0.305054)
			(end 0.12065 -0.2794)
			(stroke
				(width 0.1)
				(type default)
			)
			(layer "B.Fab")
		)
		(fp_line
			(start -0.12065 -0.3048)
			(end -0.67945 -0.3048)
			(stroke
				(width 0.1)
				(type default)
			)
			(layer "B.Fab")
		)
		(fp_line
			(start -0.67945 -0.3048)
			(end -0.67945 0.3048)
			(stroke
				(width 0.1)
				(type default)
			)
			(layer "B.Fab")
		)
		(fp_line
			(start 0.12065 -0.2794)
			(end -0.12065 -0.2794)
			(stroke
				(width 0.1)
				(type default)
			)
			(layer "B.Fab")
		)
		(fp_line
			(start -0.12065 -0.2794)
			(end -0.12065 -0.3048)
			(stroke
				(width 0.1)
				(type default)
			)
			(layer "B.Fab")
		)
		(fp_line
			(start 0.12065 0.2794)
			(end 0.12065 0.3048)
			(stroke
				(width 0.1)
				(type default)
			)
			(layer "B.Fab")
		)
		(fp_line
			(start -0.120396 0.2794)
			(end 0.12065 0.2794)
			(stroke
				(width 0.1)
				(type default)
			)
			(layer "B.Fab")
		)
		(fp_line
			(start 0.67945 0.3048)
			(end 0.67945 -0.305054)
			(stroke
				(width 0.1)
				(type default)
			)
			(layer "B.Fab")
		)
		(fp_line
			(start 0.12065 0.3048)
			(end 0.67945 0.3048)
			(stroke
				(width 0.1)
				(type default)
			)
			(layer "B.Fab")
		)
		(fp_line
			(start -0.120396 0.3048)
			(end -0.120396 0.2794)
			(stroke
				(width 0.1)
				(type default)
			)
			(layer "B.Fab")
		)
		(fp_line
			(start -0.67945 0.3048)
			(end -0.120396 0.3048)
			(stroke
				(width 0.1)
				(type default)
			)
			(layer "B.Fab")
		)
		(pad "1" smd circle
			(at 0.40005 0 270)
			(size 0 0)
			(layers "B.Cu" "B.Mask" "B.Paste")
			(net "SKU_ID_1")
		)
		(pad "2" smd circle
			(at -0.40005 0 270)
			(size 0 0)
			(layers "B.Cu" "B.Mask" "B.Paste")
			(net "GND")
		)
	)
	(footprint ""
		(layer "B.Cu")
		(at 211.455 -90.551 90)
		(property "Reference" "C7"
			(at 0 0 90)
			(layer "B.SilkS")
			(hide yes)
			(effects
				(font
					(size 1.27 1.27)
				)
				(justify mirror)
			)
		)
		(property "Value" ""
			(at 0 0 90)
			(layer "B.Fab")
			(effects
				(font
					(size 1.27 1.27)
				)
				(justify mirror)
			)
		)
		(duplicate_pad_numbers_are_jumpers no)
		(fp_line
			(start 0.7874 -0.4064)
			(end -0.7874 -0.4064)
			(stroke
				(width 0.1524)
				(type default)
			)
			(layer "B.SilkS")
		)
		(fp_line
			(start -0.7874 -0.4064)
			(end -0.7874 0.4064)
			(stroke
				(width 0.1524)
				(type default)
			)
			(layer "B.SilkS")
		)
		(fp_line
			(start 0.7874 0.4064)
			(end 0.7874 -0.4064)
			(stroke
				(width 0.1524)
				(type default)
			)
			(layer "B.SilkS")
		)
		(fp_line
			(start -0.7874 0.4064)
			(end 0.7874 0.4064)
			(stroke
				(width 0.1524)
				(type default)
			)
			(layer "B.SilkS")
		)
		(fp_line
			(start 0.67945 -0.305054)
			(end 0.12065 -0.305054)
			(stroke
				(width 0.1)
				(type default)
			)
			(layer "B.Fab")
		)
		(fp_line
			(start 0.12065 -0.305054)
			(end 0.12065 -0.2794)
			(stroke
				(width 0.1)
				(type default)
			)
			(layer "B.Fab")
		)
		(fp_line
			(start -0.12065 -0.3048)
			(end -0.67945 -0.3048)
			(stroke
				(width 0.1)
				(type default)
			)
			(layer "B.Fab")
		)
		(fp_line
			(start -0.67945 -0.3048)
			(end -0.67945 0.3048)
			(stroke
				(width 0.1)
				(type default)
			)
			(layer "B.Fab")
		)
		(fp_line
			(start 0.12065 -0.2794)
			(end -0.12065 -0.2794)
			(stroke
				(width 0.1)
				(type default)
			)
			(layer "B.Fab")
		)
		(fp_line
			(start -0.12065 -0.2794)
			(end -0.12065 -0.3048)
			(stroke
				(width 0.1)
				(type default)
			)
			(layer "B.Fab")
		)
		(fp_line
			(start 0.12065 0.2794)
			(end 0.12065 0.3048)
			(stroke
				(width 0.1)
				(type default)
			)
			(layer "B.Fab")
		)
		(fp_line
			(start -0.120396 0.2794)
			(end 0.12065 0.2794)
			(stroke
				(width 0.1)
				(type default)
			)
			(layer "B.Fab")
		)
		(fp_line
			(start 0.67945 0.3048)
			(end 0.67945 -0.305054)
			(stroke
				(width 0.1)
				(type default)
			)
			(layer "B.Fab")
		)
		(fp_line
			(start 0.12065 0.3048)
			(end 0.67945 0.3048)
			(stroke
				(width 0.1)
				(type default)
			)
			(layer "B.Fab")
		)
		(fp_line
			(start -0.120396 0.3048)
			(end -0.120396 0.2794)
			(stroke
				(width 0.1)
				(type default)
			)
			(layer "B.Fab")
		)
		(fp_line
			(start -0.67945 0.3048)
			(end -0.120396 0.3048)
			(stroke
				(width 0.1)
				(type default)
			)
			(layer "B.Fab")
		)
		(pad "1" smd circle
			(at 0.40005 0 270)
			(size 0 0)
			(layers "B.Cu" "B.Mask" "B.Paste")
			(net "GND")
		)
		(pad "2" smd circle
			(at -0.40005 0 270)
			(size 0 0)
			(layers "B.Cu" "B.Mask" "B.Paste")
			(net "P3V3_AUX")
		)
	)
	(footprint ""
		(layer "B.Cu")
		(at 287.528 -45.466 -90)
		(property "Reference" "R5904"
			(at 0 0 90)
			(layer "B.SilkS")
			(hide yes)
			(effects
				(font
					(size 1.27 1.27)
				)
				(justify mirror)
			)
		)
		(property "Value" ""
			(at 0 0 90)
			(layer "B.Fab")
			(effects
				(font
					(size 1.27 1.27)
				)
				(justify mirror)
			)
		)
		(duplicate_pad_numbers_are_jumpers no)
		(fp_line
			(start -0.7874 0.4064)
			(end 0.7874 0.4064)
			(stroke
				(width 0.1524)
				(type default)
			)
			(layer "B.SilkS")
		)
		(fp_line
			(start 0.7874 0.4064)
			(end 0.7874 -0.4064)
			(stroke
				(width 0.1524)
				(type default)
			)
			(layer "B.SilkS")
		)
		(fp_line
			(start -0.7874 -0.4064)
			(end -0.7874 0.4064)
			(stroke
				(width 0.1524)
				(type default)
			)
			(layer "B.SilkS")
		)
		(fp_line
			(start 0.7874 -0.4064)
			(end -0.7874 -0.4064)
			(stroke
				(width 0.1524)
				(type default)
			)
			(layer "B.SilkS")
		)
		(fp_line
			(start -0.67945 0.3048)
			(end -0.120396 0.3048)
			(stroke
				(width 0.1)
				(type default)
			)
			(layer "B.Fab")
		)
		(fp_line
			(start -0.120396 0.3048)
			(end -0.120396 0.2794)
			(stroke
				(width 0.1)
				(type default)
			)
			(layer "B.Fab")
		)
		(fp_line
			(start 0.12065 0.3048)
			(end 0.67945 0.3048)
			(stroke
				(width 0.1)
				(type default)
			)
			(layer "B.Fab")
		)
		(fp_line
			(start 0.67945 0.3048)
			(end 0.67945 -0.305054)
			(stroke
				(width 0.1)
				(type default)
			)
			(layer "B.Fab")
		)
		(fp_line
			(start -0.120396 0.2794)
			(end 0.12065 0.2794)
			(stroke
				(width 0.1)
				(type default)
			)
			(layer "B.Fab")
		)
		(fp_line
			(start 0.12065 0.2794)
			(end 0.12065 0.3048)
			(stroke
				(width 0.1)
				(type default)
			)
			(layer "B.Fab")
		)
		(fp_line
			(start -0.12065 -0.2794)
			(end -0.12065 -0.3048)
			(stroke
				(width 0.1)
				(type default)
			)
			(layer "B.Fab")
		)
		(fp_line
			(start 0.12065 -0.2794)
			(end -0.12065 -0.2794)
			(stroke
				(width 0.1)
				(type default)
			)
			(layer "B.Fab")
		)
		(fp_line
			(start -0.67945 -0.3048)
			(end -0.67945 0.3048)
			(stroke
				(width 0.1)
				(type default)
			)
			(layer "B.Fab")
		)
		(fp_line
			(start -0.12065 -0.3048)
			(end -0.67945 -0.3048)
			(stroke
				(width 0.1)
				(type default)
			)
			(layer "B.Fab")
		)
		(fp_line
			(start 0.12065 -0.305054)
			(end 0.12065 -0.2794)
			(stroke
				(width 0.1)
				(type default)
			)
			(layer "B.Fab")
		)
		(fp_line
			(start 0.67945 -0.305054)
			(end 0.12065 -0.305054)
			(stroke
				(width 0.1)
				(type default)
			)
			(layer "B.Fab")
		)
		(pad "1" smd circle
			(at 0.40005 0 90)
			(size 0 0)
			(layers "B.Cu" "B.Mask" "B.Paste")
			(net "FM_AC_PWR_CYCLE_N")
		)
		(pad "2" smd circle
			(at -0.40005 0 90)
			(size 0 0)
			(layers "B.Cu" "B.Mask" "B.Paste")
			(net "FM_AC_PWR_CYCLE_R_N")
		)
	)
	(footprint ""
		(layer "B.Cu")
		(at 236.982 -73.533 -90)
		(property "Reference" "C14"
			(at 0 0 90)
			(layer "B.SilkS")
			(hide yes)
			(effects
				(font
					(size 1.27 1.27)
				)
				(justify mirror)
			)
		)
		(property "Value" ""
			(at 0 0 90)
			(layer "B.Fab")
			(effects
				(font
					(size 1.27 1.27)
				)
				(justify mirror)
			)
		)
		(duplicate_pad_numbers_are_jumpers no)
		(fp_line
			(start -0.7874 0.4064)
			(end 0.7874 0.4064)
			(stroke
				(width 0.1524)
				(type default)
			)
			(layer "B.SilkS")
		)
		(fp_line
			(start 0.7874 0.4064)
			(end 0.7874 -0.4064)
			(stroke
				(width 0.1524)
				(type default)
			)
			(layer "B.SilkS")
		)
		(fp_line
			(start -0.7874 -0.4064)
			(end -0.7874 0.4064)
			(stroke
				(width 0.1524)
				(type default)
			)
			(layer "B.SilkS")
		)
		(fp_line
			(start 0.7874 -0.4064)
			(end -0.7874 -0.4064)
			(stroke
				(width 0.1524)
				(type default)
			)
			(layer "B.SilkS")
		)
		(fp_line
			(start -0.67945 0.3048)
			(end -0.120396 0.3048)
			(stroke
				(width 0.1)
				(type default)
			)
			(layer "B.Fab")
		)
		(fp_line
			(start -0.120396 0.3048)
			(end -0.120396 0.2794)
			(stroke
				(width 0.1)
				(type default)
			)
			(layer "B.Fab")
		)
		(fp_line
			(start 0.12065 0.3048)
			(end 0.67945 0.3048)
			(stroke
				(width 0.1)
				(type default)
			)
			(layer "B.Fab")
		)
		(fp_line
			(start 0.67945 0.3048)
			(end 0.67945 -0.305054)
			(stroke
				(width 0.1)
				(type default)
			)
			(layer "B.Fab")
		)
		(fp_line
			(start -0.120396 0.2794)
			(end 0.12065 0.2794)
			(stroke
				(width 0.1)
				(type default)
			)
			(layer "B.Fab")
		)
		(fp_line
			(start 0.12065 0.2794)
			(end 0.12065 0.3048)
			(stroke
				(width 0.1)
				(type default)
			)
			(layer "B.Fab")
		)
		(fp_line
			(start -0.12065 -0.2794)
			(end -0.12065 -0.3048)
			(stroke
				(width 0.1)
				(type default)
			)
			(layer "B.Fab")
		)
		(fp_line
			(start 0.12065 -0.2794)
			(end -0.12065 -0.2794)
			(stroke
				(width 0.1)
				(type default)
			)
			(layer "B.Fab")
		)
		(fp_line
			(start -0.67945 -0.3048)
			(end -0.67945 0.3048)
			(stroke
				(width 0.1)
				(type default)
			)
			(layer "B.Fab")
		)
		(fp_line
			(start -0.12065 -0.3048)
			(end -0.67945 -0.3048)
			(stroke
				(width 0.1)
				(type default)
			)
			(layer "B.Fab")
		)
		(fp_line
			(start 0.12065 -0.305054)
			(end 0.12065 -0.2794)
			(stroke
				(width 0.1)
				(type default)
			)
			(layer "B.Fab")
		)
		(fp_line
			(start 0.67945 -0.305054)
			(end 0.12065 -0.305054)
			(stroke
				(width 0.1)
				(type default)
			)
			(layer "B.Fab")
		)
		(pad "1" smd circle
			(at 0.40005 0 90)
			(size 0 0)
			(layers "B.Cu" "B.Mask" "B.Paste")
			(net "RST_SMB_PDB_R_N")
		)
		(pad "2" smd circle
			(at -0.40005 0 90)
			(size 0 0)
			(layers "B.Cu" "B.Mask" "B.Paste")
			(net "GND")
		)
	)
	(footprint ""
		(layer "B.Cu")
		(at 220.726 -90.043 -90)
		(property "Reference" "R42"
			(at 0 0 90)
			(layer "B.SilkS")
			(hide yes)
			(effects
				(font
					(size 1.27 1.27)
				)
				(justify mirror)
			)
		)
		(property "Value" ""
			(at 0 0 90)
			(layer "B.Fab")
			(effects
				(font
					(size 1.27 1.27)
				)
				(justify mirror)
			)
		)
		(duplicate_pad_numbers_are_jumpers no)
		(fp_line
			(start -0.7874 0.4064)
			(end 0.7874 0.4064)
			(stroke
				(width 0.1524)
				(type default)
			)
			(layer "B.SilkS")
		)
		(fp_line
			(start 0.7874 0.4064)
			(end 0.7874 -0.4064)
			(stroke
				(width 0.1524)
				(type default)
			)
			(layer "B.SilkS")
		)
		(fp_line
			(start -0.7874 -0.4064)
			(end -0.7874 0.4064)
			(stroke
				(width 0.1524)
				(type default)
			)
			(layer "B.SilkS")
		)
		(fp_line
			(start 0.7874 -0.4064)
			(end -0.7874 -0.4064)
			(stroke
				(width 0.1524)
				(type default)
			)
			(layer "B.SilkS")
		)
		(fp_line
			(start -0.67945 0.3048)
			(end -0.120396 0.3048)
			(stroke
				(width 0.1)
				(type default)
			)
			(layer "B.Fab")
		)
		(fp_line
			(start -0.120396 0.3048)
			(end -0.120396 0.2794)
			(stroke
				(width 0.1)
				(type default)
			)
			(layer "B.Fab")
		)
		(fp_line
			(start 0.12065 0.3048)
			(end 0.67945 0.3048)
			(stroke
				(width 0.1)
				(type default)
			)
			(layer "B.Fab")
		)
		(fp_line
			(start 0.67945 0.3048)
			(end 0.67945 -0.305054)
			(stroke
				(width 0.1)
				(type default)
			)
			(layer "B.Fab")
		)
		(fp_line
			(start -0.120396 0.2794)
			(end 0.12065 0.2794)
			(stroke
				(width 0.1)
				(type default)
			)
			(layer "B.Fab")
		)
		(fp_line
			(start 0.12065 0.2794)
			(end 0.12065 0.3048)
			(stroke
				(width 0.1)
				(type default)
			)
			(layer "B.Fab")
		)
		(fp_line
			(start -0.12065 -0.2794)
			(end -0.12065 -0.3048)
			(stroke
				(width 0.1)
				(type default)
			)
			(layer "B.Fab")
		)
		(fp_line
			(start 0.12065 -0.2794)
			(end -0.12065 -0.2794)
			(stroke
				(width 0.1)
				(type default)
			)
			(layer "B.Fab")
		)
		(fp_line
			(start -0.67945 -0.3048)
			(end -0.67945 0.3048)
			(stroke
				(width 0.1)
				(type default)
			)
			(layer "B.Fab")
		)
		(fp_line
			(start -0.12065 -0.3048)
			(end -0.67945 -0.3048)
			(stroke
				(width 0.1)
				(type default)
			)
			(layer "B.Fab")
		)
		(fp_line
			(start 0.12065 -0.305054)
			(end 0.12065 -0.2794)
			(stroke
				(width 0.1)
				(type default)
			)
			(layer "B.Fab")
		)
		(fp_line
			(start 0.67945 -0.305054)
			(end 0.12065 -0.305054)
			(stroke
				(width 0.1)
				(type default)
			)
			(layer "B.Fab")
		)
		(pad "1" smd circle
			(at 0.40005 0 90)
			(size 0 0)
			(layers "B.Cu" "B.Mask" "B.Paste")
			(net "SMB_FRU_CLK")
		)
		(pad "2" smd circle
			(at -0.40005 0 90)
			(size 0 0)
			(layers "B.Cu" "B.Mask" "B.Paste")
			(net "SMB_VPDB_MISC_SCL")
		)
	)
	(footprint ""
		(layer "B.Cu")
		(at 189.611 -86.995)
		(property "Reference" "R106"
			(at 0 0 0)
			(layer "B.SilkS")
			(hide yes)
			(effects
				(font
					(size 1.27 1.27)
				)
				(justify mirror)
			)
		)
		(property "Value" ""
			(at 0 0 0)
			(layer "B.Fab")
			(effects
				(font
					(size 1.27 1.27)
				)
				(justify mirror)
			)
		)
		(duplicate_pad_numbers_are_jumpers no)
		(fp_line
			(start -0.7874 -0.4064)
			(end -0.7874 0.4064)
			(stroke
				(width 0.1524)
				(type default)
			)
			(layer "B.SilkS")
		)
		(fp_line
			(start -0.7874 0.4064)
			(end 0.7874 0.4064)
			(stroke
				(width 0.1524)
				(type default)
			)
			(layer "B.SilkS")
		)
		(fp_line
			(start 0.7874 -0.4064)
			(end -0.7874 -0.4064)
			(stroke
				(width 0.1524)
				(type default)
			)
			(layer "B.SilkS")
		)
		(fp_line
			(start 0.7874 0.4064)
			(end 0.7874 -0.4064)
			(stroke
				(width 0.1524)
				(type default)
			)
			(layer "B.SilkS")
		)
		(fp_line
			(start -0.67945 -0.3048)
			(end -0.67945 0.3048)
			(stroke
				(width 0.1)
				(type default)
			)
			(layer "B.Fab")
		)
		(fp_line
			(start -0.67945 0.3048)
			(end -0.120396 0.3048)
			(stroke
				(width 0.1)
				(type default)
			)
			(layer "B.Fab")
		)
		(fp_line
			(start -0.12065 -0.3048)
			(end -0.67945 -0.3048)
			(stroke
				(width 0.1)
				(type default)
			)
			(layer "B.Fab")
		)
		(fp_line
			(start -0.12065 -0.2794)
			(end -0.12065 -0.3048)
			(stroke
				(width 0.1)
				(type default)
			)
			(layer "B.Fab")
		)
		(fp_line
			(start -0.120396 0.2794)
			(end 0.12065 0.2794)
			(stroke
				(width 0.1)
				(type default)
			)
			(layer "B.Fab")
		)
		(fp_line
			(start -0.120396 0.3048)
			(end -0.120396 0.2794)
			(stroke
				(width 0.1)
				(type default)
			)
			(layer "B.Fab")
		)
		(fp_line
			(start 0.12065 -0.305054)
			(end 0.12065 -0.2794)
			(stroke
				(width 0.1)
				(type default)
			)
			(layer "B.Fab")
		)
		(fp_line
			(start 0.12065 -0.2794)
			(end -0.12065 -0.2794)
			(stroke
				(width 0.1)
				(type default)
			)
			(layer "B.Fab")
		)
		(fp_line
			(start 0.12065 0.2794)
			(end 0.12065 0.3048)
			(stroke
				(width 0.1)
				(type default)
			)
			(layer "B.Fab")
		)
		(fp_line
			(start 0.12065 0.3048)
			(end 0.67945 0.3048)
			(stroke
				(width 0.1)
				(type default)
			)
			(layer "B.Fab")
		)
		(fp_line
			(start 0.67945 -0.305054)
			(end 0.12065 -0.305054)
			(stroke
				(width 0.1)
				(type default)
			)
			(layer "B.Fab")
		)
		(fp_line
			(start 0.67945 0.3048)
			(end 0.67945 -0.305054)
			(stroke
				(width 0.1)
				(type default)
			)
			(layer "B.Fab")
		)
		(pad "1" smd circle
			(at 0.40005 0 180)
			(size 0 0)
			(layers "B.Cu" "B.Mask" "B.Paste")
			(net "PU_9543_1_INT1")
		)
		(pad "2" smd circle
			(at -0.40005 0 180)
			(size 0 0)
			(layers "B.Cu" "B.Mask" "B.Paste")
			(net "P3V3_AUX")
		)
	)
)
